(kicad_pcb
	(version 20260206)
	(generator "pcbnew")
	(generator_version "10.0")
	(general
		(thickness 1.6)
		(legacy_teardrops no)
	)
	(paper "A4")
	(title_block
		(title "v2-pdb — ms_pdb_v2.brd")
		(comment 1 "Open CloudServer (Microsoft) / footprint 338 of 348 (J12), pads 1-46 of 46")
	)
	(layers
		(0 "F.Cu" signal "TOP")
		(4 "In1.Cu" signal "GND")
		(6 "In2.Cu" signal "IN1")
		(8 "In3.Cu" signal "VCC")
		(10 "In4.Cu" signal "VCC1")
		(12 "In5.Cu" signal "IN2")
		(14 "In6.Cu" signal "GND1")
		(2 "B.Cu" signal "BOTTOM")
		(9 "F.Adhes" user "F.Adhesive")
		(11 "B.Adhes" user "B.Adhesive")
		(13 "F.Paste" user "Package Geometry/Pastemask Top")
		(15 "B.Paste" user "Package Geometry/Pastemask Bottom")
		(5 "F.SilkS" user "Ref Des/Silkscreen Top")
		(7 "B.SilkS" user "Ref Des/Silkscreen Bottom")
		(1 "F.Mask" user "Board Geometry/Soldermask Top")
		(3 "B.Mask" user "Board Geometry/Soldermask Bottom")
		(17 "Dwgs.User" user "User.Drawings")
		(19 "Cmts.User" user "User.Comments")
		(21 "Eco1.User" user "User.Eco1")
		(23 "Eco2.User" user "User.Eco2")
		(25 "Edge.Cuts" user "Board Geometry/Outline")
		(27 "Margin" user)
		(31 "F.CrtYd" user "Package Geometry/Place Bound Top")
		(29 "B.CrtYd" user "Package Geometry/Place Bound Bottom")
		(35 "F.Fab" user "Ref Des/Assembly Top")
		(33 "B.Fab" user "Ref Des/Assembly Bottom")
	)
	(footprint ""
		(layer "B.Cu")
		(at 44.03979 -230.51008 90)
		(property "Reference" "J12"
			(at 6.153658 -3.773932 0)
			(unlocked yes)
			(layer "B.SilkS")
			(effects
				(font
					(size 0.7874 0.5842)
					(thickness 0.1524)
				)
				(justify left mirror)
			)
		)
		(property "Value" ""
			(at 0 0 90)
			(layer "B.Fab")
			(effects
				(font
					(size 1.27 1.27)
				)
				(justify mirror)
			)
		)
		(duplicate_pad_numbers_are_jumpers no)
		(pad "" np_thru_hole circle
			(at -1.35001 -2.54)
			(size 2.5146 2.5146)
			(drill 2.5146)
			(layers "*.Cu" "*.Mask")
			(clearance 0.381)
			(thermal_gap 0.381)
		)
		(pad "" np_thru_hole circle
			(at 0 50.8)
			(size 2.5146 2.5146)
			(drill 2.5146)
			(layers "*.Cu" "*.Mask")
			(clearance 0.381)
			(thermal_gap 0.381)
		)
		(pad "P1" thru_hole rect
			(at 0 0)
			(size 1.1684 1.1684)
			(drill 0.762)
			(layers "*.Cu" "*.Mask")
			(remove_unused_layers no)
			(net "GND")
			(clearance 0.0508)
			(padstack
				(mode front_inner_back)
				(layer "Inner"
					(shape circle)
					(size 1.1684 1.1684)
					(clearance 0.0508)
				)
				(layer "B.Cu"
					(shape rect)
					(size 1.1684 1.1684)
					(thermal_gap 0.0508)
					(clearance 0.0508)
				)
			)
		)
		(pad "P2" thru_hole circle
			(at 0 2.54)
			(size 1.1684 1.1684)
			(drill 0.762)
			(layers "*.Cu" "*.Mask")
			(remove_unused_layers no)
			(net "GND")
			(clearance 0.0508)
			(thermal_gap 0.0508)
		)
		(pad "P3" thru_hole circle
			(at 0 5.08)
			(size 1.1684 1.1684)
			(drill 0.762)
			(layers "*.Cu" "*.Mask")
			(remove_unused_layers no)
			(net "GND")
			(clearance 0.0508)
			(thermal_gap 0.0508)
		)
		(pad "P4" thru_hole circle
			(at 0 7.62)
			(size 1.1684 1.1684)
			(drill 0.762)
			(layers "*.Cu" "*.Mask")
			(remove_unused_layers no)
			(net "GND")
			(clearance 0.0508)
			(thermal_gap 0.0508)
		)
		(pad "P5" thru_hole circle
			(at 0 10.16)
			(size 1.1684 1.1684)
			(drill 0.762)
			(layers "*.Cu" "*.Mask")
			(remove_unused_layers no)
			(net "GND")
			(clearance 0.0508)
			(thermal_gap 0.0508)
		)
		(pad "P6" thru_hole circle
			(at 0 12.7)
			(size 1.1684 1.1684)
			(drill 0.762)
			(layers "*.Cu" "*.Mask")
			(remove_unused_layers no)
			(net "GND")
			(clearance 0.0508)
			(thermal_gap 0.0508)
		)
		(pad "P7" thru_hole circle
			(at 0 15.24)
			(size 1.1684 1.1684)
			(drill 0.762)
			(layers "*.Cu" "*.Mask")
			(remove_unused_layers no)
			(net "GND")
			(clearance 0.0508)
			(thermal_gap 0.0508)
		)
		(pad "P8" thru_hole circle
			(at 0 17.78)
			(size 1.1684 1.1684)
			(drill 0.762)
			(layers "*.Cu" "*.Mask")
			(remove_unused_layers no)
			(net "GND")
			(clearance 0.0508)
			(thermal_gap 0.0508)
		)
		(pad "P9" thru_hole circle
			(at 0 20.32)
			(size 1.1684 1.1684)
			(drill 0.762)
			(layers "*.Cu" "*.Mask")
			(remove_unused_layers no)
			(net "P12V")
			(clearance 0.0508)
			(thermal_gap 0.0508)
		)
		(pad "P10" thru_hole circle
			(at 0 22.86)
			(size 1.1684 1.1684)
			(drill 0.762)
			(layers "*.Cu" "*.Mask")
			(remove_unused_layers no)
			(net "P12V")
			(clearance 0.0508)
			(thermal_gap 0.0508)
		)
		(pad "P11" thru_hole circle
			(at 0 25.4)
			(size 1.1684 1.1684)
			(drill 0.762)
			(layers "*.Cu" "*.Mask")
			(remove_unused_layers no)
			(net "P12V")
			(clearance 0.0508)
			(thermal_gap 0.0508)
		)
		(pad "P12" thru_hole circle
			(at 0 27.94)
			(size 1.1684 1.1684)
			(drill 0.762)
			(layers "*.Cu" "*.Mask")
			(remove_unused_layers no)
			(net "P12V")
			(clearance 0.0508)
			(thermal_gap 0.0508)
		)
		(pad "P13" thru_hole circle
			(at 0 30.48)
			(size 1.1684 1.1684)
			(drill 0.762)
			(layers "*.Cu" "*.Mask")
			(remove_unused_layers no)
			(net "P12V")
			(clearance 0.0508)
			(thermal_gap 0.0508)
		)
		(pad "P14" thru_hole circle
			(at 0 33.02)
			(size 1.1684 1.1684)
			(drill 0.762)
			(layers "*.Cu" "*.Mask")
			(remove_unused_layers no)
			(net "P12V")
			(clearance 0.0508)
			(thermal_gap 0.0508)
		)
		(pad "P15" thru_hole circle
			(at 0 35.56)
			(size 1.1684 1.1684)
			(drill 0.762)
			(layers "*.Cu" "*.Mask")
			(remove_unused_layers no)
			(net "P12V")
			(clearance 0.0508)
			(thermal_gap 0.0508)
		)
		(pad "P16" thru_hole circle
			(at 0 38.1)
			(size 1.1684 1.1684)
			(drill 0.762)
			(layers "*.Cu" "*.Mask")
			(remove_unused_layers no)
			(net "P12V")
			(clearance 0.0508)
			(thermal_gap 0.0508)
		)
		(pad "P17" thru_hole circle
			(at -2.70002 38.1)
			(size 1.1684 1.1684)
			(drill 0.762)
			(layers "*.Cu" "*.Mask")
			(remove_unused_layers no)
			(net "P12V")
			(clearance 0.0508)
			(thermal_gap 0.0508)
		)
		(pad "P18" thru_hole circle
			(at -2.70002 35.56)
			(size 1.1684 1.1684)
			(drill 0.762)
			(layers "*.Cu" "*.Mask")
			(remove_unused_layers no)
			(net "P12V")
			(clearance 0.0508)
			(thermal_gap 0.0508)
		)
		(pad "P19" thru_hole circle
			(at -2.70002 33.02)
			(size 1.1684 1.1684)
			(drill 0.762)
			(layers "*.Cu" "*.Mask")
			(remove_unused_layers no)
			(net "P12V")
			(clearance 0.0508)
			(thermal_gap 0.0508)
		)
		(pad "P20" thru_hole circle
			(at -2.70002 30.48)
			(size 1.1684 1.1684)
			(drill 0.762)
			(layers "*.Cu" "*.Mask")
			(remove_unused_layers no)
			(net "P12V")
			(clearance 0.0508)
			(thermal_gap 0.0508)
		)
		(pad "P21" thru_hole circle
			(at -2.70002 27.94)
			(size 1.1684 1.1684)
			(drill 0.762)
			(layers "*.Cu" "*.Mask")
			(remove_unused_layers no)
			(net "P12V")
			(clearance 0.0508)
			(thermal_gap 0.0508)
		)
		(pad "P22" thru_hole circle
			(at -2.70002 25.4)
			(size 1.1684 1.1684)
			(drill 0.762)
			(layers "*.Cu" "*.Mask")
			(remove_unused_layers no)
			(net "P12V")
			(clearance 0.0508)
			(thermal_gap 0.0508)
		)
		(pad "P23" thru_hole circle
			(at -2.70002 22.86)
			(size 1.1684 1.1684)
			(drill 0.762)
			(layers "*.Cu" "*.Mask")
			(remove_unused_layers no)
			(net "P12V")
			(clearance 0.0508)
			(thermal_gap 0.0508)
		)
		(pad "P24" thru_hole circle
			(at -2.70002 20.32)
			(size 1.1684 1.1684)
			(drill 0.762)
			(layers "*.Cu" "*.Mask")
			(remove_unused_layers no)
			(net "P12V")
			(clearance 0.0508)
			(thermal_gap 0.0508)
		)
		(pad "P25" thru_hole circle
			(at -2.70002 17.78)
			(size 1.1684 1.1684)
			(drill 0.762)
			(layers "*.Cu" "*.Mask")
			(remove_unused_layers no)
			(net "GND")
			(clearance 0.0508)
			(thermal_gap 0.0508)
		)
		(pad "P26" thru_hole circle
			(at -2.70002 15.24)
			(size 1.1684 1.1684)
			(drill 0.762)
			(layers "*.Cu" "*.Mask")
			(remove_unused_layers no)
			(net "GND")
			(clearance 0.0508)
			(thermal_gap 0.0508)
		)
		(pad "P27" thru_hole circle
			(at -2.70002 12.7)
			(size 1.1684 1.1684)
			(drill 0.762)
			(layers "*.Cu" "*.Mask")
			(remove_unused_layers no)
			(net "GND")
			(clearance 0.0508)
			(thermal_gap 0.0508)
		)
		(pad "P28" thru_hole circle
			(at -2.70002 10.16)
			(size 1.1684 1.1684)
			(drill 0.762)
			(layers "*.Cu" "*.Mask")
			(remove_unused_layers no)
			(net "GND")
			(clearance 0.0508)
			(thermal_gap 0.0508)
		)
		(pad "P29" thru_hole circle
			(at -2.70002 7.62)
			(size 1.1684 1.1684)
			(drill 0.762)
			(layers "*.Cu" "*.Mask")
			(remove_unused_layers no)
			(net "GND")
			(clearance 0.0508)
			(thermal_gap 0.0508)
		)
		(pad "P30" thru_hole circle
			(at -2.70002 5.08)
			(size 1.1684 1.1684)
			(drill 0.762)
			(layers "*.Cu" "*.Mask")
			(remove_unused_layers no)
			(net "GND")
			(clearance 0.0508)
			(thermal_gap 0.0508)
		)
		(pad "P31" thru_hole circle
			(at -2.70002 2.54)
			(size 1.1684 1.1684)
			(drill 0.762)
			(layers "*.Cu" "*.Mask")
			(remove_unused_layers no)
			(net "GND")
			(clearance 0.0508)
			(thermal_gap 0.0508)
		)
		(pad "P32" thru_hole circle
			(at -2.70002 0)
			(size 1.1684 1.1684)
			(drill 0.762)
			(layers "*.Cu" "*.Mask")
			(remove_unused_layers no)
			(net "GND")
			(clearance 0.0508)
			(thermal_gap 0.0508)
		)
		(pad "S1" thru_hole circle
			(at 0.55499 41.60012)
			(size 1.1684 1.1684)
			(drill 0.762)
			(layers "*.Cu" "*.Mask")
			(remove_unused_layers no)
			(net "T6_BLAD1_TXD")
			(clearance 0.0508)
			(thermal_gap 0.0508)
		)
		(pad "S2" thru_hole circle
			(at -0.71501 42.87012)
			(size 1.1684 1.1684)
			(drill 0.762)
			(layers "*.Cu" "*.Mask")
			(remove_unused_layers no)
			(net "T6_BLAD1_RXD")
			(clearance 0.0508)
			(thermal_gap 0.0508)
		)
		(pad "S3" thru_hole circle
			(at 0.55499 44.14012)
			(size 1.1684 1.1684)
			(drill 0.762)
			(layers "*.Cu" "*.Mask")
			(remove_unused_layers no)
			(net "T6_BLAD1_EN")
			(clearance 0.0508)
			(thermal_gap 0.0508)
		)
		(pad "S4" thru_hole circle
			(at -0.71501 45.41012)
			(size 1.1684 1.1684)
			(drill 0.762)
			(layers "*.Cu" "*.Mask")
			(remove_unused_layers no)
			(net "B11_PSU_ALERT_N")
			(clearance 0.0508)
			(thermal_gap 0.0508)
		)
		(pad "S5" thru_hole circle
			(at 0.55499 46.68012)
			(size 1.1684 1.1684)
			(drill 0.762)
			(layers "*.Cu" "*.Mask")
			(remove_unused_layers no)
			(net "T6_BLAD2_TXD")
			(clearance 0.0508)
			(thermal_gap 0.0508)
		)
		(pad "S6" thru_hole circle
			(at -0.71501 47.95012)
			(size 1.1684 1.1684)
			(drill 0.762)
			(layers "*.Cu" "*.Mask")
			(remove_unused_layers no)
			(net "T6_BLAD2_RXD")
			(clearance 0.0508)
			(thermal_gap 0.0508)
		)
		(pad "S7" thru_hole circle
			(at -3.25501 47.95012)
			(size 1.1684 1.1684)
			(drill 0.762)
			(layers "*.Cu" "*.Mask")
			(remove_unused_layers no)
			(net "T6_BLAD4_RXD")
			(clearance 0.0508)
			(thermal_gap 0.0508)
		)
		(pad "S8" thru_hole circle
			(at -1.98501 46.68012)
			(size 1.1684 1.1684)
			(drill 0.762)
			(layers "*.Cu" "*.Mask")
			(remove_unused_layers no)
			(net "T6_BLAD4_TXD")
			(clearance 0.0508)
			(thermal_gap 0.0508)
		)
		(pad "S9" thru_hole circle
			(at -3.25501 45.41012)
			(size 1.1684 1.1684)
			(drill 0.762)
			(layers "*.Cu" "*.Mask")
			(remove_unused_layers no)
			(net "B12_PSU_ALERT_N")
			(clearance 0.0508)
			(thermal_gap 0.0508)
		)
		(pad "S10" thru_hole circle
			(at -1.98501 44.14012)
			(size 1.1684 1.1684)
			(drill 0.762)
			(layers "*.Cu" "*.Mask")
			(remove_unused_layers no)
			(net "T6_BLAD3_EN")
			(clearance 0.0508)
			(thermal_gap 0.0508)
		)
		(pad "S11" thru_hole circle
			(at -3.25501 42.87012)
			(size 1.1684 1.1684)
			(drill 0.762)
			(layers "*.Cu" "*.Mask")
			(remove_unused_layers no)
			(net "T6_BLAD3_RXD")
			(clearance 0.0508)
			(thermal_gap 0.0508)
		)
		(pad "S12" thru_hole circle
			(at -1.98501 41.60012)
			(size 1.1684 1.1684)
			(drill 0.762)
			(layers "*.Cu" "*.Mask")
			(remove_unused_layers no)
			(net "T6_BLAD3_TXD")
			(clearance 0.0508)
			(thermal_gap 0.0508)
		)
	)
)
